(kicad_pcb
	(version 20260206)
	(generator "pcbnew")
	(generator_version "10.0")
	(general
		(thickness 1.6)
		(legacy_teardrops no)
	)
	(paper "A4")
	(title_block
		(title "Wiwynn_Tioga_Pass_MB.brd")
		(comment 1 "Tioga Pass / footprint 190 of 4770 (U2D1), pads 80-192 of 3647")
	)
	(layers
		(0 "F.Cu" signal "TOP")
		(4 "In1.Cu" signal "L2GND")
		(6 "In2.Cu" signal "L3")
		(8 "In3.Cu" signal "L4GND")
		(10 "In4.Cu" signal "L5")
		(12 "In5.Cu" signal "L6GND")
		(14 "In6.Cu" signal "L7VCC")
		(16 "In7.Cu" signal "L8VCC")
		(18 "In8.Cu" signal "L9GND")
		(20 "In9.Cu" signal "L10")
		(22 "In10.Cu" signal "L11GND")
		(24 "In11.Cu" signal "L12")
		(26 "In12.Cu" signal "L13GND")
		(2 "B.Cu" signal "BOTTOM")
		(9 "F.Adhes" user "F.Adhesive")
		(11 "B.Adhes" user "B.Adhesive")
		(13 "F.Paste" user "Package Geometry/Pastemask Top")
		(15 "B.Paste" user "Package Geometry/Pastemask Bottom")
		(5 "F.SilkS" user "Ref Des/Silkscreen Top")
		(7 "B.SilkS" user "Ref Des/Silkscreen Bottom")
		(1 "F.Mask" user "Board Geometry/Soldermask Top")
		(3 "B.Mask" user "Board Geometry/Soldermask Bottom")
		(17 "Dwgs.User" user "User.Drawings")
		(19 "Cmts.User" user "User.Comments")
		(21 "Eco1.User" user "User.Eco1")
		(23 "Eco2.User" user "User.Eco2")
		(25 "Edge.Cuts" user "Board Geometry/Outline")
		(27 "Margin" user)
		(31 "F.CrtYd" user "Package Geometry/Place Bound Top")
		(29 "B.CrtYd" user "Package Geometry/Place Bound Bottom")
		(35 "F.Fab" user "Ref Des/Assembly Top")
		(33 "B.Fab" user "Ref Des/Assembly Bottom")
	)
	(footprint ""
		(layer "F.Cu")
		(at 104.99979 -76.550012 180)
		(property "Reference" "U2D1"
			(at 25.19299 30.484318 0)
			(unlocked yes)
			(layer "F.SilkS")
			(effects
				(font
					(size 0.7874 0.5842)
					(thickness 0.1524)
				)
			)
		)
		(property "Value" ""
			(at 0 0 180)
			(layer "F.Fab")
			(effects
				(font
					(size 1.27 1.27)
				)
			)
		)
		(duplicate_pad_numbers_are_jumpers no)
		(pad "AB41" smd circle
			(at -2.910586 -14.702028)
			(size 0.4318 0.4318)
			(layers "F.Cu" "F.Mask" "F.Paste")
			(net "GND")
		)
		(pad "AB43" smd circle
			(at -1.193546 -14.702028)
			(size 0.4318 0.4318)
			(layers "F.Cu" "F.Mask" "F.Paste")
			(net "A_CPU1_GHJ_RCOMP1")
		)
		(pad "AB45" smd circle
			(at 2.052066 -16.502126)
			(size 0.508 0.508)
			(layers "F.Cu" "F.Mask" "F.Paste")
			(net "M_J_C<2>")
		)
		(pad "AB47" smd circle
			(at 3.769106 -16.502126)
			(size 0.4318 0.4318)
			(layers "F.Cu" "F.Mask" "F.Paste")
			(net "M_J_ODT<3>")
		)
		(pad "AB49" smd circle
			(at 5.485892 -16.502126)
			(size 0.4318 0.4318)
			(layers "F.Cu" "F.Mask" "F.Paste")
			(net "M_J_CS_N<1>")
		)
		(pad "AB51" smd circle
			(at 7.202932 -16.502126)
			(size 0.4318 0.4318)
			(layers "F.Cu" "F.Mask" "F.Paste")
			(net "M_J_CS_N<4>")
		)
		(pad "AB53" smd circle
			(at 8.919972 -16.502126)
			(size 0.4318 0.4318)
			(layers "F.Cu" "F.Mask" "F.Paste")
			(net "M_J_MA<0>")
		)
		(pad "AB55" smd circle
			(at 10.637012 -16.502126)
			(size 0.4318 0.4318)
			(layers "F.Cu" "F.Mask" "F.Paste")
			(net "M_J_CLK_DP<0>")
		)
		(pad "AB57" smd circle
			(at 12.354052 -16.502126)
			(size 0.4318 0.4318)
			(layers "F.Cu" "F.Mask" "F.Paste")
			(net "M_J_CLK_DP<2>")
		)
		(pad "AB59" smd circle
			(at 14.071092 -16.502126)
			(size 0.4318 0.4318)
			(layers "F.Cu" "F.Mask" "F.Paste")
			(net "M_J_MA<6>")
		)
		(pad "AB61" smd circle
			(at 15.787878 -16.502126)
			(size 0.4318 0.4318)
			(layers "F.Cu" "F.Mask" "F.Paste")
			(net "M_J_ACT_N")
		)
		(pad "AB63" smd circle
			(at 17.504918 -16.502126)
			(size 0.4318 0.4318)
			(layers "F.Cu" "F.Mask" "F.Paste")
			(net "M_J_CKE<3>")
		)
		(pad "AB65" smd circle
			(at 19.221958 -16.502126)
			(size 0.4318 0.4318)
			(layers "F.Cu" "F.Mask" "F.Paste")
			(net "GND")
		)
		(pad "AB67" smd circle
			(at 20.938998 -16.502126)
			(size 0.4318 0.4318)
			(layers "F.Cu" "F.Mask" "F.Paste")
			(net "M_G_DQS_DN<17>")
		)
		(pad "AB69" smd circle
			(at 22.656038 -16.502126)
			(size 0.4318 0.4318)
			(layers "F.Cu" "F.Mask" "F.Paste")
			(net "GND")
		)
		(pad "AB71" smd circle
			(at 24.373078 -16.502126)
			(size 0.4318 0.4318)
			(layers "F.Cu" "F.Mask" "F.Paste")
			(net "M_J_DQ<21>")
		)
		(pad "AB73" smd circle
			(at 26.090118 -16.502126)
			(size 0.4318 0.4318)
			(layers "F.Cu" "F.Mask" "F.Paste")
			(net "GND")
		)
		(pad "AB75" smd circle
			(at 27.806904 -16.502126)
			(size 0.4318 0.4318)
			(layers "F.Cu" "F.Mask" "F.Paste")
			(net "M_J_DQS_DP<1>")
		)
		(pad "AB77" smd circle
			(at 29.523944 -16.502126)
			(size 0.4318 0.4318)
			(layers "F.Cu" "F.Mask" "F.Paste")
			(net "M_J_DQ<14>")
		)
		(pad "AB79" smd circle
			(at 31.240984 -16.502126)
			(size 0.4318 0.4318)
			(layers "F.Cu" "F.Mask" "F.Paste")
			(net "GND")
		)
		(pad "AB81" smd circle
			(at 32.958024 -16.502126)
			(size 0.4318 0.4318)
			(layers "F.Cu" "F.Mask" "F.Paste")
			(net "M_H_DQ<11>")
		)
		(pad "AB83" smd circle
			(at 34.675064 -16.502126)
			(size 0.4318 0.4318)
			(layers "F.Cu" "F.Mask" "F.Paste")
			(net "GND")
		)
		(pad "AB85" smd circle
			(at 36.392104 -16.502126)
			(size 0.4318 0.4318)
			(layers "F.Cu" "F.Mask" "F.Paste")
			(net "GND")
		)
		(pad "AC2" smd circle
			(at -36.392104 -14.206474)
			(size 0.4318 0.4318)
			(layers "F.Cu" "F.Mask" "F.Paste")
			(net "UPI_CPU1_CPU0_P0P0_DP<5>")
		)
		(pad "AC4" smd circle
			(at -34.675064 -14.206474)
			(size 0.4318 0.4318)
			(layers "F.Cu" "F.Mask" "F.Paste")
			(net "PVCCIO_CPU1")
		)
		(pad "AC6" smd circle
			(at -32.958024 -14.206474)
			(size 0.4318 0.4318)
			(layers "F.Cu" "F.Mask" "F.Paste")
			(net "UPI_CPU0_CPU1_P0P0_DN<3>")
		)
		(pad "AC8" smd circle
			(at -31.240984 -14.206474)
			(size 0.4318 0.4318)
			(layers "F.Cu" "F.Mask" "F.Paste")
			(net "UPI_CPU0_CPU1_P0P0_DP<1>")
		)
		(pad "AC10" smd circle
			(at -29.523944 -14.206474)
			(size 0.4318 0.4318)
			(layers "F.Cu" "F.Mask" "F.Paste")
			(net "UPI_CPU0_CPU1_P0P0_DP<0>")
		)
		(pad "AC12" smd circle
			(at -27.806904 -14.206474)
			(size 0.4318 0.4318)
			(layers "F.Cu" "F.Mask" "F.Paste")
			(net "XDP_CPU_OBSFN_B1_MBP7_N")
		)
		(pad "AC14" smd circle
			(at -26.090118 -14.206474)
			(size 0.4318 0.4318)
			(layers "F.Cu" "F.Mask" "F.Paste")
			(net "XDP_CPU1_TDI")
		)
		(pad "AC16" smd circle
			(at -24.373078 -14.206474)
			(size 0.4318 0.4318)
			(layers "F.Cu" "F.Mask" "F.Paste")
			(net "H_CPU1_PROCHOT_G_N")
		)
		(pad "AC18" smd circle
			(at -22.656038 -14.206474)
			(size 0.4318 0.4318)
			(layers "F.Cu" "F.Mask" "F.Paste")
			(net "GND")
		)
		(pad "AC20" smd circle
			(at -20.938998 -14.206474)
			(size 0.4318 0.4318)
			(layers "F.Cu" "F.Mask" "F.Paste")
			(net "PVCCIO_CPU1")
		)
		(pad "AC22" smd circle
			(at -19.221958 -14.206474)
			(size 0.4318 0.4318)
			(layers "F.Cu" "F.Mask" "F.Paste")
			(net "GND")
		)
		(pad "AC24" smd circle
			(at -17.504918 -14.206474)
			(size 0.4318 0.4318)
			(layers "F.Cu" "F.Mask" "F.Paste")
			(net "M_J_DQS_DN<16>")
		)
		(pad "AC26" smd circle
			(at -15.787878 -14.206474)
			(size 0.4318 0.4318)
			(layers "F.Cu" "F.Mask" "F.Paste")
			(net "GND")
		)
		(pad "AC28" smd circle
			(at -14.071092 -14.206474)
			(size 0.4318 0.4318)
			(layers "F.Cu" "F.Mask" "F.Paste")
			(net "GND")
		)
		(pad "AC30" smd circle
			(at -12.354052 -14.206474)
			(size 0.4318 0.4318)
			(layers "F.Cu" "F.Mask" "F.Paste")
			(net "M_J_DQS_DN<15>")
		)
		(pad "AC32" smd circle
			(at -10.637012 -14.206474)
			(size 0.4318 0.4318)
			(layers "F.Cu" "F.Mask" "F.Paste")
			(net "GND")
		)
		(pad "AC34" smd circle
			(at -8.919972 -14.206474)
			(size 0.4318 0.4318)
			(layers "F.Cu" "F.Mask" "F.Paste")
			(net "GND")
		)
		(pad "AC36" smd circle
			(at -7.202932 -14.206474)
			(size 0.4318 0.4318)
			(layers "F.Cu" "F.Mask" "F.Paste")
			(net "PVCCIO_CPU1")
		)
		(pad "AC38" smd circle
			(at -5.485892 -14.206474)
			(size 0.4318 0.4318)
			(layers "F.Cu" "F.Mask" "F.Paste")
			(net "GND")
		)
		(pad "AC40" smd circle
			(at -3.769106 -14.206474)
			(size 0.4318 0.4318)
			(layers "F.Cu" "F.Mask" "F.Paste")
			(net "GND")
		)
		(pad "AC42" smd circle
			(at -2.052066 -14.206474)
			(size 0.4318 0.4318)
			(layers "F.Cu" "F.Mask" "F.Paste")
			(net "A_CPU1_GHJ_RCOMP2")
		)
		(pad "AC46" smd circle
			(at 2.910586 -16.006572)
			(size 0.4318 0.4318)
			(layers "F.Cu" "F.Mask" "F.Paste")
			(net "M_J_MA<17>")
		)
		(pad "AC48" smd circle
			(at 4.627626 -16.006572)
			(size 0.4318 0.4318)
			(layers "F.Cu" "F.Mask" "F.Paste")
			(net "GND")
		)
		(pad "AC50" smd circle
			(at 6.344412 -16.006572)
			(size 0.4318 0.4318)
			(layers "F.Cu" "F.Mask" "F.Paste")
			(net "GND")
		)
		(pad "AC52" smd circle
			(at 8.061452 -16.006572)
			(size 0.4318 0.4318)
			(layers "F.Cu" "F.Mask" "F.Paste")
			(net "GND")
		)
		(pad "AC54" smd circle
			(at 9.778492 -16.006572)
			(size 0.4318 0.4318)
			(layers "F.Cu" "F.Mask" "F.Paste")
			(net "GND")
		)
		(pad "AC56" smd circle
			(at 11.495532 -16.006572)
			(size 0.4318 0.4318)
			(layers "F.Cu" "F.Mask" "F.Paste")
			(net "GND")
		)
		(pad "AC58" smd circle
			(at 13.212572 -16.006572)
			(size 0.4318 0.4318)
			(layers "F.Cu" "F.Mask" "F.Paste")
			(net "GND")
		)
		(pad "AC60" smd circle
			(at 14.929612 -16.006572)
			(size 0.4318 0.4318)
			(layers "F.Cu" "F.Mask" "F.Paste")
			(net "GND")
		)
		(pad "AC62" smd circle
			(at 16.646398 -16.006572)
			(size 0.4318 0.4318)
			(layers "F.Cu" "F.Mask" "F.Paste")
			(net "GND")
		)
		(pad "AC64" smd circle
			(at 18.363438 -16.006572)
			(size 0.4318 0.4318)
			(layers "F.Cu" "F.Mask" "F.Paste")
			(net "GND")
		)
		(pad "AC66" smd circle
			(at 20.080478 -16.006572)
			(size 0.4318 0.4318)
			(layers "F.Cu" "F.Mask" "F.Paste")
			(net "M_G_ECC<6>")
		)
		(pad "AC68" smd circle
			(at 21.797518 -16.006572)
			(size 0.4318 0.4318)
			(layers "F.Cu" "F.Mask" "F.Paste")
			(net "M_G_ECC<0>")
		)
		(pad "AC70" smd circle
			(at 23.514558 -16.006572)
			(size 0.4318 0.4318)
			(layers "F.Cu" "F.Mask" "F.Paste")
			(net "GND")
		)
		(pad "AC72" smd circle
			(at 25.231598 -16.006572)
			(size 0.4318 0.4318)
			(layers "F.Cu" "F.Mask" "F.Paste")
			(net "GND")
		)
		(pad "AC74" smd circle
			(at 26.948384 -16.006572)
			(size 0.4318 0.4318)
			(layers "F.Cu" "F.Mask" "F.Paste")
			(net "M_J_DQ<9>")
		)
		(pad "AC76" smd circle
			(at 28.665424 -16.006572)
			(size 0.4318 0.4318)
			(layers "F.Cu" "F.Mask" "F.Paste")
			(net "M_J_DQS_DP<10>")
		)
		(pad "AC78" smd circle
			(at 30.382464 -16.006572)
			(size 0.4318 0.4318)
			(layers "F.Cu" "F.Mask" "F.Paste")
			(net "GND")
		)
		(pad "AC80" smd circle
			(at 32.099504 -16.006572)
			(size 0.4318 0.4318)
			(layers "F.Cu" "F.Mask" "F.Paste")
			(net "M_H_DQ<15>")
		)
		(pad "AC82" smd circle
			(at 33.816544 -16.006572)
			(size 0.4318 0.4318)
			(layers "F.Cu" "F.Mask" "F.Paste")
			(net "M_H_DQ<10>")
		)
		(pad "AC84" smd circle
			(at 35.533584 -16.006572)
			(size 0.4318 0.4318)
			(layers "F.Cu" "F.Mask" "F.Paste")
			(net "GND")
		)
		(pad "AC86" smd custom
			(at 37.250624 -16.006572 270)
			(size 0.10795 0.10795)
			(layers "F.Cu" "F.Mask" "F.Paste")
			(net "GND")
			(options
				(clearance outline)
				(anchor circle)
			)
			(primitives
				(gr_poly
					(pts
						(arc
							(start 0.2159 -0.0381)
							(mid 0 -0.254)
							(end -0.2159 -0.0381)
						)
						(arc
							(start -0.2159 0.0381)
							(mid 0 0.254)
							(end 0.2159 0.0381)
						)
					)
					(width 0)
					(fill yes)
				)
			)
		)
		(pad "AD1" smd custom
			(at -37.250624 -13.711428 90)
			(size 0.10795 0.10795)
			(layers "F.Cu" "F.Mask" "F.Paste")
			(net "UPI_CPU1_CPU0_P0P0_DN<5>")
			(options
				(clearance outline)
				(anchor circle)
			)
			(primitives
				(gr_poly
					(pts
						(arc
							(start 0.2159 -0.0381)
							(mid 0 -0.254)
							(end -0.2159 -0.0381)
						)
						(arc
							(start -0.2159 0.0381)
							(mid 0 0.254)
							(end 0.2159 0.0381)
						)
					)
					(width 0)
					(fill yes)
				)
			)
		)
		(pad "AD3" smd circle
			(at -35.533584 -13.711428)
			(size 0.4318 0.4318)
			(layers "F.Cu" "F.Mask" "F.Paste")
			(net "GND")
		)
		(pad "AD5" smd circle
			(at -33.816544 -13.711428)
			(size 0.4318 0.4318)
			(layers "F.Cu" "F.Mask" "F.Paste")
			(net "UPI_CPU0_CPU1_P0P0_DP<3>")
		)
		(pad "AD7" smd circle
			(at -32.099504 -13.711428)
			(size 0.4318 0.4318)
			(layers "F.Cu" "F.Mask" "F.Paste")
			(net "GND")
		)
		(pad "AD9" smd circle
			(at -30.382464 -13.711428)
			(size 0.4318 0.4318)
			(layers "F.Cu" "F.Mask" "F.Paste")
			(net "GND")
		)
		(pad "AD11" smd circle
			(at -28.665424 -13.711428)
			(size 0.4318 0.4318)
			(layers "F.Cu" "F.Mask" "F.Paste")
			(net "GND")
		)
		(pad "AD13" smd circle
			(at -26.948384 -13.711428)
			(size 0.4318 0.4318)
			(layers "F.Cu" "F.Mask" "F.Paste")
			(net "GND")
		)
		(pad "AD15" smd circle
			(at -25.231598 -13.711428)
			(size 0.4318 0.4318)
			(layers "F.Cu" "F.Mask" "F.Paste")
			(net "GND")
		)
		(pad "AD17" smd circle
			(at -23.514558 -13.711428)
			(size 0.4318 0.4318)
			(layers "F.Cu" "F.Mask" "F.Paste")
			(net "SMB_DDR_KLM_SDA_G_R")
		)
		(pad "AD19" smd circle
			(at -21.797518 -13.711428)
			(size 0.4318 0.4318)
			(layers "F.Cu" "F.Mask" "F.Paste")
			(net "GND")
		)
		(pad "AD21" smd circle
			(at -20.080478 -13.711428)
			(size 0.4318 0.4318)
			(layers "F.Cu" "F.Mask" "F.Paste")
			(net "GND")
		)
		(pad "AD23" smd circle
			(at -18.363438 -13.711428)
			(size 0.4318 0.4318)
			(layers "F.Cu" "F.Mask" "F.Paste")
			(net "M_J_DQ<62>")
		)
		(pad "AD25" smd circle
			(at -16.646398 -13.711428)
			(size 0.4318 0.4318)
			(layers "F.Cu" "F.Mask" "F.Paste")
			(net "M_J_DQ<56>")
		)
		(pad "AD27" smd circle
			(at -14.929612 -13.711428)
			(size 0.4318 0.4318)
			(layers "F.Cu" "F.Mask" "F.Paste")
			(net "GND")
		)
		(pad "AD29" smd circle
			(at -13.212572 -13.711428)
			(size 0.4318 0.4318)
			(layers "F.Cu" "F.Mask" "F.Paste")
			(net "M_J_DQ<54>")
		)
		(pad "AD31" smd circle
			(at -11.495532 -13.711428)
			(size 0.4318 0.4318)
			(layers "F.Cu" "F.Mask" "F.Paste")
			(net "M_J_DQ<48>")
		)
		(pad "AD33" smd circle
			(at -9.778492 -13.711428)
			(size 0.4318 0.4318)
			(layers "F.Cu" "F.Mask" "F.Paste")
			(net "GND")
		)
		(pad "AD35" smd circle
			(at -8.061452 -13.711428)
			(size 0.4318 0.4318)
			(layers "F.Cu" "F.Mask" "F.Paste")
			(net "PVCCIO_CPU1")
		)
		(pad "AD37" smd circle
			(at -6.344412 -13.711428)
			(size 0.4318 0.4318)
			(layers "F.Cu" "F.Mask" "F.Paste")
			(net "PVCCIO_CPU1")
		)
		(pad "AD39" smd circle
			(at -4.627626 -13.711428)
			(size 0.4318 0.4318)
			(layers "F.Cu" "F.Mask" "F.Paste")
			(net "GND")
		)
		(pad "AD41" smd circle
			(at -2.910586 -13.711428)
			(size 0.4318 0.4318)
			(layers "F.Cu" "F.Mask" "F.Paste")
			(net "VSENSE_PMAX_CPU1")
		)
		(pad "AD43" smd circle
			(at -1.193546 -13.711428)
			(size 0.4318 0.4318)
			(layers "F.Cu" "F.Mask" "F.Paste")
			(net "GND")
		)
		(pad "AD45" smd circle
			(at 2.052066 -15.511526)
			(size 0.508 0.508)
			(layers "F.Cu" "F.Mask" "F.Paste")
			(net "PVDDQ_GHJ")
		)
		(pad "AD47" smd circle
			(at 3.769106 -15.511526)
			(size 0.4318 0.4318)
			(layers "F.Cu" "F.Mask" "F.Paste")
			(net "TP_CPU1_RSVD_254")
		)
		(pad "AD49" smd circle
			(at 5.485892 -15.511526)
			(size 0.4318 0.4318)
			(layers "F.Cu" "F.Mask" "F.Paste")
			(net "TP_CPU1_RSVD_253")
		)
		(pad "AD51" smd circle
			(at 7.202932 -15.511526)
			(size 0.4318 0.4318)
			(layers "F.Cu" "F.Mask" "F.Paste")
			(net "TP_CPU1_RSVD_252")
		)
		(pad "AD53" smd circle
			(at 8.919972 -15.511526)
			(size 0.4318 0.4318)
			(layers "F.Cu" "F.Mask" "F.Paste")
			(net "M_J_MA<13>")
		)
		(pad "AD55" smd circle
			(at 10.637012 -15.511526)
			(size 0.4318 0.4318)
			(layers "F.Cu" "F.Mask" "F.Paste")
			(net "M_J_MA<10>")
		)
		(pad "AD57" smd circle
			(at 12.354052 -15.511526)
			(size 0.4318 0.4318)
			(layers "F.Cu" "F.Mask" "F.Paste")
			(net "M_J_MA<2>")
		)
		(pad "AD59" smd circle
			(at 14.071092 -15.511526)
			(size 0.4318 0.4318)
			(layers "F.Cu" "F.Mask" "F.Paste")
			(net "M_J_MA<8>")
		)
		(pad "AD61" smd circle
			(at 15.787878 -15.511526)
			(size 0.4318 0.4318)
			(layers "F.Cu" "F.Mask" "F.Paste")
			(net "M_J_ALERT_N")
		)
		(pad "AD63" smd circle
			(at 17.504918 -15.511526)
			(size 0.4318 0.4318)
			(layers "F.Cu" "F.Mask" "F.Paste")
			(net "M_J_CKE<1>")
		)
		(pad "AD65" smd circle
			(at 19.221958 -15.511526)
			(size 0.4318 0.4318)
			(layers "F.Cu" "F.Mask" "F.Paste")
			(net "M_G_ECC<2>")
		)
		(pad "AD67" smd circle
			(at 20.938998 -15.511526)
			(size 0.4318 0.4318)
			(layers "F.Cu" "F.Mask" "F.Paste")
			(net "M_G_DQS_DP<17>")
		)
		(pad "AD69" smd circle
			(at 22.656038 -15.511526)
			(size 0.4318 0.4318)
			(layers "F.Cu" "F.Mask" "F.Paste")
			(net "M_G_ECC<4>")
		)
		(pad "AD71" smd circle
			(at 24.373078 -15.511526)
			(size 0.4318 0.4318)
			(layers "F.Cu" "F.Mask" "F.Paste")
			(net "GND")
		)
		(pad "AD73" smd circle
			(at 26.090118 -15.511526)
			(size 0.4318 0.4318)
			(layers "F.Cu" "F.Mask" "F.Paste")
			(net "GND")
		)
		(pad "AD75" smd circle
			(at 27.806904 -15.511526)
			(size 0.4318 0.4318)
			(layers "F.Cu" "F.Mask" "F.Paste")
			(net "GND")
		)
		(pad "AD77" smd circle
			(at 29.523944 -15.511526)
			(size 0.4318 0.4318)
			(layers "F.Cu" "F.Mask" "F.Paste")
			(net "M_J_DQS_DN<10>")
		)
		(pad "AD79" smd circle
			(at 31.240984 -15.511526)
			(size 0.4318 0.4318)
			(layers "F.Cu" "F.Mask" "F.Paste")
			(net "M_H_DQS_DN<1>")
		)
		(pad "AD81" smd circle
			(at 32.958024 -15.511526)
			(size 0.4318 0.4318)
			(layers "F.Cu" "F.Mask" "F.Paste")
			(net "GND")
		)
		(pad "AD83" smd circle
			(at 34.675064 -15.511526)
			(size 0.4318 0.4318)
			(layers "F.Cu" "F.Mask" "F.Paste")
			(net "GND")
		)
		(pad "AD85" smd circle
			(at 36.392104 -15.511526)
			(size 0.4318 0.4318)
			(layers "F.Cu" "F.Mask" "F.Paste")
			(net "GND")
		)
		(pad "AE2" smd circle
			(at -36.392104 -13.215874)
			(size 0.4318 0.4318)
			(layers "F.Cu" "F.Mask" "F.Paste")
			(net "UPI_CPU1_CPU0_P0P0_DN<7>")
		)
		(pad "AE4" smd circle
			(at -34.675064 -13.215874)
			(size 0.4318 0.4318)
			(layers "F.Cu" "F.Mask" "F.Paste")
			(net "GND")
		)
		(pad "AE6" smd circle
			(at -32.958024 -13.215874)
			(size 0.4318 0.4318)
			(layers "F.Cu" "F.Mask" "F.Paste")
			(net "UPI_CPU0_CPU1_P0P0_DP<4>")
		)
		(pad "AE8" smd circle
			(at -31.240984 -13.215874)
			(size 0.4318 0.4318)
			(layers "F.Cu" "F.Mask" "F.Paste")
			(net "GND")
		)
		(pad "AE10" smd circle
			(at -29.523944 -13.215874)
			(size 0.4318 0.4318)
			(layers "F.Cu" "F.Mask" "F.Paste")
			(net "PVCCIO_CPU1")
		)
	)
)
